# S9S_MB_2U (Grand Teton) — schematic netlist excerpt (pin names and nets, part order shuffled) for the footprints in the layout excerpt that follows; sources: Cadence DE-HDL packaged netlist, KiCad conversion of 03242023_DA0F0TMBIJ0_F0T_Motherboard_J_brd_V01_OCP.brd

R4209  Q_RES  200K 1% EMPTY  pkg 0402LF  page 170 : A = P3V3_AUX ; B = FM_THERMAL_ALERT_N
PR4528  Q_RES  10M 1% EMPTY  pkg 0402LF  page 192 : A = P12V_E1S_0 ; B = P12V_E1S_GATE_0

(kicad_pcb
	(version 20260206)
	(generator "pcbnew")
	(generator_version "10.0")
	(general
		(thickness 1.6)
		(legacy_teardrops no)
	)
	(paper "A4")
	(title_block
		(title "03242023_DA0F0TMBIJ0_F0T_Motherboard_J_brd_V01_OCP.brd")
		(comment 1 "Grand Teton / footprints 1278-1279 of 6105")
	)
	(layers
		(0 "F.Cu" signal "TOP")
		(4 "In1.Cu" signal "GND")
		(6 "In2.Cu" signal "IN1")
		(8 "In3.Cu" signal "GND1")
		(10 "In4.Cu" signal "IN2")
		(12 "In5.Cu" signal "GND2")
		(14 "In6.Cu" signal "IN3")
		(16 "In7.Cu" signal "GND3")
		(18 "In8.Cu" signal "VCC")
		(20 "In9.Cu" signal "VCC1")
		(22 "In10.Cu" signal "GND4")
		(24 "In11.Cu" signal "IN4")
		(26 "In12.Cu" signal "GND5")
		(28 "In13.Cu" signal "IN5")
		(30 "In14.Cu" signal "GND6")
		(32 "In15.Cu" signal "IN6")
		(34 "In16.Cu" signal "GND7")
		(2 "B.Cu" signal "BOTTOM")
		(9 "F.Adhes" user "F.Adhesive")
		(11 "B.Adhes" user "B.Adhesive")
		(13 "F.Paste" user "Package Geometry/Pastemask Top")
		(15 "B.Paste" user "Package Geometry/Pastemask Bottom")
		(5 "F.SilkS" user "Ref Des/Silkscreen Top")
		(7 "B.SilkS" user "Ref Des/Silkscreen Bottom")
		(1 "F.Mask" user "Board Geometry/Soldermask Top")
		(3 "B.Mask" user "Board Geometry/Soldermask Bottom")
		(17 "Dwgs.User" user "User.Drawings")
		(19 "Cmts.User" user "User.Comments")
		(21 "Eco1.User" user "User.Eco1")
		(23 "Eco2.User" user "User.Eco2")
		(25 "Edge.Cuts" user "Board Geometry/Outline")
		(27 "Margin" user)
		(31 "F.CrtYd" user "Package Geometry/Place Bound Top")
		(29 "B.CrtYd" user "Package Geometry/Place Bound Bottom")
		(35 "F.Fab" user "Ref Des/Assembly Top")
		(33 "B.Fab" user "Ref Des/Assembly Bottom")
	)
	(footprint ""
		(layer "F.Cu")
		(at 257.87985 -39.484046 90)
		(property "Reference" "PR4528"
			(at 0 0 90)
			(layer "F.SilkS")
			(hide yes)
			(effects
				(font
					(size 1.27 1.27)
				)
			)
		)
		(property "Value" ""
			(at 0 0 90)
			(layer "F.Fab")
			(effects
				(font
					(size 1.27 1.27)
				)
			)
		)
		(duplicate_pad_numbers_are_jumpers no)
		(fp_line
			(start 0.7874 -0.4064)
			(end 0.7874 0.4064)
			(stroke
				(width 0.1524)
				(type default)
			)
			(layer "F.SilkS")
		)
		(fp_line
			(start -0.7874 -0.4064)
			(end 0.7874 -0.4064)
			(stroke
				(width 0.1524)
				(type default)
			)
			(layer "F.SilkS")
		)
		(fp_line
			(start 0.7874 0.4064)
			(end -0.7874 0.4064)
			(stroke
				(width 0.1524)
				(type default)
			)
			(layer "F.SilkS")
		)
		(fp_line
			(start -0.7874 0.4064)
			(end -0.7874 -0.4064)
			(stroke
				(width 0.1524)
				(type default)
			)
			(layer "F.SilkS")
		)
		(fp_line
			(start -0.12065 -0.305054)
			(end -0.12065 -0.2794)
			(stroke
				(width 0.1)
				(type default)
			)
			(layer "F.Fab")
		)
		(fp_line
			(start -0.67945 -0.305054)
			(end -0.12065 -0.305054)
			(stroke
				(width 0.1)
				(type default)
			)
			(layer "F.Fab")
		)
		(fp_line
			(start 0.67945 -0.3048)
			(end 0.67945 0.3048)
			(stroke
				(width 0.1)
				(type default)
			)
			(layer "F.Fab")
		)
		(fp_line
			(start 0.12065 -0.3048)
			(end 0.67945 -0.3048)
			(stroke
				(width 0.1)
				(type default)
			)
			(layer "F.Fab")
		)
		(fp_line
			(start 0.12065 -0.2794)
			(end 0.12065 -0.3048)
			(stroke
				(width 0.1)
				(type default)
			)
			(layer "F.Fab")
		)
		(fp_line
			(start -0.12065 -0.2794)
			(end 0.12065 -0.2794)
			(stroke
				(width 0.1)
				(type default)
			)
			(layer "F.Fab")
		)
		(fp_line
			(start 0.120396 0.2794)
			(end -0.12065 0.2794)
			(stroke
				(width 0.1)
				(type default)
			)
			(layer "F.Fab")
		)
		(fp_line
			(start -0.12065 0.2794)
			(end -0.12065 0.3048)
			(stroke
				(width 0.1)
				(type default)
			)
			(layer "F.Fab")
		)
		(fp_line
			(start 0.67945 0.3048)
			(end 0.120396 0.3048)
			(stroke
				(width 0.1)
				(type default)
			)
			(layer "F.Fab")
		)
		(fp_line
			(start 0.120396 0.3048)
			(end 0.120396 0.2794)
			(stroke
				(width 0.1)
				(type default)
			)
			(layer "F.Fab")
		)
		(fp_line
			(start -0.12065 0.3048)
			(end -0.67945 0.3048)
			(stroke
				(width 0.1)
				(type default)
			)
			(layer "F.Fab")
		)
		(fp_line
			(start -0.67945 0.3048)
			(end -0.67945 -0.305054)
			(stroke
				(width 0.1)
				(type default)
			)
			(layer "F.Fab")
		)
		(pad "1" smd circle
			(at -0.40005 0 90)
			(size 0 0)
			(layers "F.Cu" "F.Mask" "F.Paste")
			(net "P12V_E1S_0")
		)
		(pad "2" smd circle
			(at 0.40005 0 90)
			(size 0 0)
			(layers "F.Cu" "F.Mask" "F.Paste")
			(net "P12V_E1S_GATE_0")
		)
	)
	(footprint ""
		(layer "F.Cu")
		(at 365.390938 -417.15309 90)
		(property "Reference" "R4209"
			(at 0 0 90)
			(layer "F.SilkS")
			(hide yes)
			(effects
				(font
					(size 1.27 1.27)
				)
			)
		)
		(property "Value" ""
			(at 0 0 90)
			(layer "F.Fab")
			(effects
				(font
					(size 1.27 1.27)
				)
			)
		)
		(duplicate_pad_numbers_are_jumpers no)
		(fp_line
			(start 0.7874 -0.4064)
			(end 0.7874 0.4064)
			(stroke
				(width 0.1524)
				(type default)
			)
			(layer "F.SilkS")
		)
		(fp_line
			(start -0.7874 -0.4064)
			(end 0.7874 -0.4064)
			(stroke
				(width 0.1524)
				(type default)
			)
			(layer "F.SilkS")
		)
		(fp_line
			(start 0.7874 0.4064)
			(end -0.7874 0.4064)
			(stroke
				(width 0.1524)
				(type default)
			)
			(layer "F.SilkS")
		)
		(fp_line
			(start -0.7874 0.4064)
			(end -0.7874 -0.4064)
			(stroke
				(width 0.1524)
				(type default)
			)
			(layer "F.SilkS")
		)
		(fp_line
			(start -0.12065 -0.305054)
			(end -0.12065 -0.2794)
			(stroke
				(width 0.1)
				(type default)
			)
			(layer "F.Fab")
		)
		(fp_line
			(start -0.67945 -0.305054)
			(end -0.12065 -0.305054)
			(stroke
				(width 0.1)
				(type default)
			)
			(layer "F.Fab")
		)
		(fp_line
			(start 0.67945 -0.3048)
			(end 0.67945 0.3048)
			(stroke
				(width 0.1)
				(type default)
			)
			(layer "F.Fab")
		)
		(fp_line
			(start 0.12065 -0.3048)
			(end 0.67945 -0.3048)
			(stroke
				(width 0.1)
				(type default)
			)
			(layer "F.Fab")
		)
		(fp_line
			(start 0.12065 -0.2794)
			(end 0.12065 -0.3048)
			(stroke
				(width 0.1)
				(type default)
			)
			(layer "F.Fab")
		)
		(fp_line
			(start -0.12065 -0.2794)
			(end 0.12065 -0.2794)
			(stroke
				(width 0.1)
				(type default)
			)
			(layer "F.Fab")
		)
		(fp_line
			(start 0.120396 0.2794)
			(end -0.12065 0.2794)
			(stroke
				(width 0.1)
				(type default)
			)
			(layer "F.Fab")
		)
		(fp_line
			(start -0.12065 0.2794)
			(end -0.12065 0.3048)
			(stroke
				(width 0.1)
				(type default)
			)
			(layer "F.Fab")
		)
		(fp_line
			(start 0.67945 0.3048)
			(end 0.120396 0.3048)
			(stroke
				(width 0.1)
				(type default)
			)
			(layer "F.Fab")
		)
		(fp_line
			(start 0.120396 0.3048)
			(end 0.120396 0.2794)
			(stroke
				(width 0.1)
				(type default)
			)
			(layer "F.Fab")
		)
		(fp_line
			(start -0.12065 0.3048)
			(end -0.67945 0.3048)
			(stroke
				(width 0.1)
				(type default)
			)
			(layer "F.Fab")
		)
		(fp_line
			(start -0.67945 0.3048)
			(end -0.67945 -0.305054)
			(stroke
				(width 0.1)
				(type default)
			)
			(layer "F.Fab")
		)
		(pad "1" smd circle
			(at -0.40005 0 90)
			(size 0 0)
			(layers "F.Cu" "F.Mask" "F.Paste")
			(net "P3V3_AUX")
		)
		(pad "2" smd circle
			(at 0.40005 0 90)
			(size 0 0)
			(layers "F.Cu" "F.Mask" "F.Paste")
			(net "FM_THERMAL_ALERT_N")
		)
	)
)
